(kicad_pcb
	(version 20241229)
	(generator "pcbnew")
	(generator_version "9.0")
	(general
		(thickness 1.63)
		(legacy_teardrops no)
	)
	(paper "A4")
	(title_block
		(title "CM4 Baseboard")
		(date "2026-01-05")
		(rev "1.1.1")
		(company "Antmicro Ltd")
		(comment 1 "www.antmicro.com")
		(comment 9 "footprints 6-10 of 506")
	)
	(layers
		(0 "F.Cu" signal)
		(4 "In1.Cu" power)
		(6 "In2.Cu" power)
		(8 "In3.Cu" signal)
		(10 "In4.Cu" signal)
		(2 "B.Cu" signal)
		(9 "F.Adhes" user "F.Adhesive")
		(11 "B.Adhes" user "B.Adhesive")
		(13 "F.Paste" user)
		(15 "B.Paste" user)
		(5 "F.SilkS" user "F.Silkscreen")
		(7 "B.SilkS" user "B.Silkscreen")
		(1 "F.Mask" user)
		(3 "B.Mask" user)
		(17 "Dwgs.User" user "User.Drawings")
		(19 "Cmts.User" user "User.Comments")
		(21 "Eco1.User" user "User.Eco1")
		(23 "Eco2.User" user "User.Eco2")
		(25 "Edge.Cuts" user)
		(27 "Margin" user)
		(31 "F.CrtYd" user "F.Courtyard")
		(29 "B.CrtYd" user "B.Courtyard")
		(35 "F.Fab" user)
		(33 "B.Fab" user)
	)
	(footprint "antmicro-footprints:R_0402_1005Metric"
		(layer "F.Cu")
		(at 46.547962 132.8365 180)
		(descr "Resistor SMD 0402")
		(tags "resistor SMD 0402")
		(property "Reference" "R403"
			(at 1.18 -0.38 0)
			(layer "F.SilkS")
			(effects
				(font
					(size 0.7 0.7)
					(thickness 0.15)
				)
				(justify right bottom)
			)
		)
		(property "Value" "R_0R_0402"
			(at -1.011843 1.772047 0)
			(layer "F.Fab")
			(effects
				(font
					(size 0.7 0.7)
					(thickness 0.15)
				)
				(justify right bottom)
			)
		)
		(property "Datasheet" "https://industrial.panasonic.com/cdbs/www-data/pdf/RDA0000/AOA0000C301.pdf"
			(at 0 0 180)
			(layer "F.Fab")
			(hide yes)
			(effects
				(font
					(size 1.27 1.27)
					(thickness 0.15)
				)
			)
		)
		(property "Manufacturer" "Panasonic"
			(at 0 0 180)
			(unlocked yes)
			(layer "F.Fab")
			(hide yes)
			(effects
				(font
					(size 1 1)
					(thickness 0.15)
				)
			)
		)
		(property "MPN" "ERJ2GE0R00X"
			(at 0 0 180)
			(unlocked yes)
			(layer "F.Fab")
			(hide yes)
			(effects
				(font
					(size 1 1)
					(thickness 0.15)
				)
			)
		)
		(property "Val" "0R"
			(at 0 0 180)
			(unlocked yes)
			(layer "F.Fab")
			(hide yes)
			(effects
				(font
					(size 1 1)
					(thickness 0.15)
				)
			)
		)
		(property "License" "Apache-2.0"
			(at 0 0 180)
			(unlocked yes)
			(layer "F.Fab")
			(hide yes)
			(effects
				(font
					(size 1 1)
					(thickness 0.15)
				)
			)
		)
		(property "Author" "Antmicro"
			(at 0 0 180)
			(unlocked yes)
			(layer "F.Fab")
			(hide yes)
			(effects
				(font
					(size 1 1)
					(thickness 0.15)
				)
			)
		)
		(property "Tolerance" "~"
			(at 0 0 180)
			(unlocked yes)
			(layer "F.Fab")
			(hide yes)
			(effects
				(font
					(size 1 1)
					(thickness 0.15)
				)
			)
		)
		(property "Current" "1A"
			(at 0 0 180)
			(unlocked yes)
			(layer "F.Fab")
			(hide yes)
			(effects
				(font
					(size 1 1)
					(thickness 0.15)
				)
			)
		)
		(sheetname "/Ethernet/")
		(sheetfile "ethernet.kicad_sch")
		(attr smd)
		(fp_rect
			(start -0.925 -0.47)
			(end 0.925 0.47)
			(stroke
				(width 0.05)
				(type default)
			)
			(fill no)
			(layer "F.CrtYd")
		)
		(fp_rect
			(start -0.5 -0.25)
			(end 0.5 0.25)
			(stroke
				(width 0.15)
				(type solid)
			)
			(fill no)
			(layer "F.Fab")
		)
		(fp_text user "Author: Antmicro"
			(at -0.95 4.169 180)
			(layer "F.Fab")
			(effects
				(font
					(size 0.7 0.7)
					(thickness 0.15)
				)
				(justify left bottom)
			)
		)
		(fp_text user "${REFERENCE}"
			(at -0.95 3.168 180)
			(layer "F.Fab")
			(effects
				(font
					(size 0.7 0.7)
					(thickness 0.15)
				)
				(justify left bottom)
			)
		)
		(fp_text user "License: Apache-2.0"
			(at -0.95 5.169 180)
			(layer "F.Fab")
			(effects
				(font
					(size 0.7 0.7)
					(thickness 0.15)
				)
				(justify left bottom)
			)
		)
		(pad "1" smd roundrect
			(at -0.48 0 180)
			(size 0.59 0.64)
			(layers "F.Cu" "F.Mask" "F.Paste")
			(roundrect_rratio 0.25)
			(net 358 "/Ethernet/MPS_DUTY")
			(pintype "passive")
		)
		(pad "2" smd roundrect
			(at 0.48 0 180)
			(size 0.59 0.64)
			(layers "F.Cu" "F.Mask" "F.Paste")
			(roundrect_rratio 0.25)
			(net 90 "/Ethernet/VSS")
			(pintype "passive")
		)
	)
	(footprint "antmicro-footprints:Switch_Slide_CAS-120TA"
		(layer "F.Cu")
		(at 141.577962 122.7665 -90)
		(property "Reference" "S203"
			(at -3.2665 -1.972038 90)
			(layer "F.SilkS")
			(effects
				(font
					(size 0.7 0.7)
					(thickness 0.15)
				)
				(justify right bottom)
			)
		)
		(property "Value" "CAS-120TA"
			(at 5.95 3.2 90)
			(layer "F.Fab")
			(effects
				(font
					(size 0.7 0.7)
					(thickness 0.15)
				)
				(justify right bottom)
			)
		)
		(property "Datasheet" "https://www.nidec-components.com/e/catalog/switch/cas.pdf"
			(at 0 0 270)
			(layer "F.Fab")
			(hide yes)
			(effects
				(font
					(size 1.27 1.27)
					(thickness 0.15)
				)
			)
		)
		(property "MPN" "CAS-120TA"
			(at 0 0 270)
			(unlocked yes)
			(layer "F.Fab")
			(hide yes)
			(effects
				(font
					(size 1 1)
					(thickness 0.15)
				)
			)
		)
		(property "Manufacturer" "Nidec Components"
			(at 0 0 270)
			(unlocked yes)
			(layer "F.Fab")
			(hide yes)
			(effects
				(font
					(size 1 1)
					(thickness 0.15)
				)
			)
		)
		(property "Author" "Antmicro"
			(at 0 0 270)
			(unlocked yes)
			(layer "F.Fab")
			(hide yes)
			(effects
				(font
					(size 1 1)
					(thickness 0.15)
				)
			)
		)
		(property "License" "Apache-2.0"
			(at 0 0 270)
			(unlocked yes)
			(layer "F.Fab")
			(hide yes)
			(effects
				(font
					(size 1 1)
					(thickness 0.15)
				)
			)
		)
		(sheetname "/Compute module/")
		(sheetfile "compute-module.kicad_sch")
		(attr smd)
		(fp_circle
			(center -3.502 1.148)
			(end -3.452 1.148)
			(stroke
				(width 0.15)
				(type solid)
			)
			(fill yes)
			(layer "F.SilkS")
		)
		(fp_rect
			(start -3.202 -1.901)
			(end 3.2 1.898)
			(stroke
				(width 0.05)
				(type solid)
			)
			(fill no)
			(layer "F.CrtYd")
		)
		(fp_line
			(start -2.9 1.148)
			(end 2.898 1.148)
			(stroke
				(width 0.15)
				(type solid)
			)
			(layer "F.Fab")
		)
		(fp_line
			(start -2.9 1.148)
			(end -2.9 -1.151)
			(stroke
				(width 0.15)
				(type solid)
			)
			(layer "F.Fab")
		)
		(fp_line
			(start 2.898 -1.151)
			(end 2.898 1.148)
			(stroke
				(width 0.15)
				(type solid)
			)
			(layer "F.Fab")
		)
		(fp_line
			(start 2.898 -1.151)
			(end -2.9 -1.151)
			(stroke
				(width 0.15)
				(type solid)
			)
			(layer "F.Fab")
		)
		(fp_text user "${REFERENCE}"
			(at -3.15 5.2 270)
			(layer "F.Fab")
			(effects
				(font
					(size 0.7 0.7)
					(thickness 0.15)
				)
				(justify left bottom)
			)
		)
		(fp_text user "License: Apache-2.0"
			(at -3.15 7.6 270)
			(layer "F.Fab")
			(effects
				(font
					(size 0.7 0.7)
					(thickness 0.15)
				)
				(justify left bottom)
			)
		)
		(fp_text user "Author: Antmicro"
			(at -3.15 6.4 270)
			(layer "F.Fab")
			(effects
				(font
					(size 0.7 0.7)
					(thickness 0.15)
				)
				(justify left bottom)
			)
		)
		(pad "1" smd rect
			(at -1.75 1.148 270)
			(size 1 1.6)
			(layers "F.Cu" "F.Mask" "F.Paste")
			(net 279 "/Compute module/USB.OTGID")
			(pintype "passive")
		)
		(pad "2" smd rect
			(at 0 -1.151 270)
			(size 1 1.6)
			(layers "F.Cu" "F.Mask" "F.Paste")
			(net 342 "Net-(R211-Pad1)")
			(pintype "passive")
		)
		(pad "3" smd rect
			(at 1.749 1.148 270)
			(size 1 1.6)
			(layers "F.Cu" "F.Mask" "F.Paste")
			(net 407 "unconnected-(S203-Pad3)")
			(pintype "passive+no_connect")
		)
	)
	(footprint "antmicro-footprints:R_0402_1005Metric"
		(layer "F.Cu")
		(at 54.817962 133.7265 180)
		(descr "Resistor SMD 0402")
		(tags "resistor SMD 0402")
		(property "Reference" "R417"
			(at -1.632038 5.2265 0)
			(layer "F.SilkS")
			(effects
				(font
					(size 0.7 0.7)
					(thickness 0.15)
				)
				(justify right bottom)
			)
		)
		(property "Value" "R_0R_0402"
			(at -1.011843 1.772047 0)
			(layer "F.Fab")
			(effects
				(font
					(size 0.7 0.7)
					(thickness 0.15)
				)
				(justify right bottom)
			)
		)
		(property "Datasheet" "https://industrial.panasonic.com/cdbs/www-data/pdf/RDA0000/AOA0000C301.pdf"
			(at 0 0 180)
			(layer "F.Fab")
			(hide yes)
			(effects
				(font
					(size 1.27 1.27)
					(thickness 0.15)
				)
			)
		)
		(property "Manufacturer" "Panasonic"
			(at 0 0 180)
			(unlocked yes)
			(layer "F.Fab")
			(hide yes)
			(effects
				(font
					(size 1 1)
					(thickness 0.15)
				)
			)
		)
		(property "MPN" "ERJ2GE0R00X"
			(at 0 0 180)
			(unlocked yes)
			(layer "F.Fab")
			(hide yes)
			(effects
				(font
					(size 1 1)
					(thickness 0.15)
				)
			)
		)
		(property "Val" "0R"
			(at 0 0 180)
			(unlocked yes)
			(layer "F.Fab")
			(hide yes)
			(effects
				(font
					(size 1 1)
					(thickness 0.15)
				)
			)
		)
		(property "License" "Apache-2.0"
			(at 0 0 180)
			(unlocked yes)
			(layer "F.Fab")
			(hide yes)
			(effects
				(font
					(size 1 1)
					(thickness 0.15)
				)
			)
		)
		(property "Author" "Antmicro"
			(at 0 0 180)
			(unlocked yes)
			(layer "F.Fab")
			(hide yes)
			(effects
				(font
					(size 1 1)
					(thickness 0.15)
				)
			)
		)
		(property "Tolerance" "~"
			(at 0 0 180)
			(unlocked yes)
			(layer "F.Fab")
			(hide yes)
			(effects
				(font
					(size 1 1)
					(thickness 0.15)
				)
			)
		)
		(property "Current" "1A"
			(at 0 0 180)
			(unlocked yes)
			(layer "F.Fab")
			(hide yes)
			(effects
				(font
					(size 1 1)
					(thickness 0.15)
				)
			)
		)
		(sheetname "/Ethernet/")
		(sheetfile "ethernet.kicad_sch")
		(attr smd exclude_from_pos_files exclude_from_bom dnp)
		(fp_rect
			(start -0.925 -0.47)
			(end 0.925 0.47)
			(stroke
				(width 0.05)
				(type default)
			)
			(fill no)
			(layer "F.CrtYd")
		)
		(fp_rect
			(start -0.5 -0.25)
			(end 0.5 0.25)
			(stroke
				(width 0.15)
				(type solid)
			)
			(fill no)
			(layer "F.Fab")
		)
		(fp_text user "License: Apache-2.0"
			(at -0.95 5.169 180)
			(layer "F.Fab")
			(effects
				(font
					(size 0.7 0.7)
					(thickness 0.15)
				)
				(justify left bottom)
			)
		)
		(fp_text user "Author: Antmicro"
			(at -0.95 4.169 180)
			(layer "F.Fab")
			(effects
				(font
					(size 0.7 0.7)
					(thickness 0.15)
				)
				(justify left bottom)
			)
		)
		(fp_text user "${REFERENCE}"
			(at -0.95 3.168 180)
			(layer "F.Fab")
			(effects
				(font
					(size 0.7 0.7)
					(thickness 0.15)
				)
				(justify left bottom)
			)
		)
		(pad "1" smd roundrect
			(at -0.48 0 180)
			(size 0.59 0.64)
			(layers "F.Cu" "F.Mask" "F.Paste")
			(roundrect_rratio 0.25)
			(net 126 "/Ethernet/ULS-12_CTRL")
			(pintype "passive")
		)
		(pad "2" smd roundrect
			(at 0.48 0 180)
			(size 0.59 0.64)
			(layers "F.Cu" "F.Mask" "F.Paste")
			(roundrect_rratio 0.25)
			(net 339 "/Ethernet/POE_ACTIVE")
			(pintype "passive")
		)
	)
	(footprint "antmicro-footprints:C_0402_1005Metric"
		(layer "F.Cu")
		(at 61.117962 177.6915 -90)
		(descr "Capacitor SMD 0402")
		(tags "capacitor SMD 0402")
		(property "Reference" "C826"
			(at -2.805 14.88 90)
			(layer "F.SilkS")
			(effects
				(font
					(size 0.7 0.7)
					(thickness 0.15)
				)
				(justify right bottom)
			)
		)
		(property "Value" "C_template_name_0402"
			(at -1.022927 2.155213 90)
			(layer "F.Fab")
			(effects
				(font
					(size 0.7 0.7)
					(thickness 0.15)
				)
				(justify right bottom)
			)
		)
		(property "Datasheet" "template_datasheet"
			(at 0 0 270)
			(layer "F.Fab")
			(hide yes)
			(effects
				(font
					(size 1.27 1.27)
					(thickness 0.15)
				)
			)
		)
		(property "MPN" "template_MPN"
			(at 0 0 270)
			(unlocked yes)
			(layer "F.Fab")
			(hide yes)
			(effects
				(font
					(size 1 1)
					(thickness 0.15)
				)
			)
		)
		(property "Manufacturer" "template_manufacturer"
			(at 0 0 270)
			(unlocked yes)
			(layer "F.Fab")
			(hide yes)
			(effects
				(font
					(size 1 1)
					(thickness 0.15)
				)
			)
		)
		(property "License" "Apache-2.0"
			(at 0 0 270)
			(unlocked yes)
			(layer "F.Fab")
			(hide yes)
			(effects
				(font
					(size 1 1)
					(thickness 0.15)
				)
			)
		)
		(property "Author" "Antmicro"
			(at 0 0 270)
			(unlocked yes)
			(layer "F.Fab")
			(hide yes)
			(effects
				(font
					(size 1 1)
					(thickness 0.15)
				)
			)
		)
		(property "Val" "template_value"
			(at 0 0 270)
			(unlocked yes)
			(layer "F.Fab")
			(hide yes)
			(effects
				(font
					(size 1 1)
					(thickness 0.15)
				)
			)
		)
		(property "Voltage" "template_voltage"
			(at 0 0 270)
			(unlocked yes)
			(layer "F.Fab")
			(hide yes)
			(effects
				(font
					(size 1 1)
					(thickness 0.15)
				)
			)
		)
		(property "Dielectric" "template_dielectric"
			(at 0 0 270)
			(unlocked yes)
			(layer "F.Fab")
			(hide yes)
			(effects
				(font
					(size 1 1)
					(thickness 0.15)
				)
			)
		)
		(sheetname "/Peripherals/")
		(sheetfile "peripherals.kicad_sch")
		(attr smd exclude_from_pos_files exclude_from_bom dnp)
		(fp_rect
			(start -0.925 -0.47)
			(end 0.925 0.47)
			(stroke
				(width 0.05)
				(type default)
			)
			(fill no)
			(layer "F.CrtYd")
		)
		(fp_line
			(start -0.494 0.248)
			(end -0.494 -0.25)
			(stroke
				(width 0.15)
				(type solid)
			)
			(layer "F.Fab")
		)
		(fp_line
			(start 0.504 0.248)
			(end -0.494 0.248)
			(stroke
				(width 0.15)
				(type solid)
			)
			(layer "F.Fab")
		)
		(fp_line
			(start -0.494 -0.25)
			(end 0.504 -0.25)
			(stroke
				(width 0.15)
				(type solid)
			)
			(layer "F.Fab")
		)
		(fp_line
			(start 0.504 -0.25)
			(end 0.504 0.248)
			(stroke
				(width 0.15)
				(type solid)
			)
			(layer "F.Fab")
		)
		(fp_text user "License: Apache-2.0"
			(at -0.939 5.799 270)
			(layer "F.Fab")
			(effects
				(font
					(size 0.7 0.7)
					(thickness 0.15)
				)
				(justify left bottom)
			)
		)
		(fp_text user "Author: Antmicro"
			(at -0.939 3.399 270)
			(layer "F.Fab")
			(effects
				(font
					(size 0.7 0.7)
					(thickness 0.15)
				)
				(justify left bottom)
			)
		)
		(fp_text user "${REFERENCE}"
			(at -0.939 4.599 270)
			(layer "F.Fab")
			(effects
				(font
					(size 0.7 0.7)
					(thickness 0.15)
				)
				(justify left bottom)
			)
		)
		(pad "1" smd roundrect
			(at -0.48 0 270)
			(size 0.59 0.64)
			(layers "F.Cu" "F.Mask" "F.Paste")
			(roundrect_rratio 0.25)
			(net 3 "GND")
			(pintype "passive")
		)
		(pad "2" smd roundrect
			(at 0.48 0 270)
			(size 0.59 0.64)
			(layers "F.Cu" "F.Mask" "F.Paste")
			(roundrect_rratio 0.25)
			(net 100 "Net-(C811-Pad2)")
			(pintype "passive")
		)
	)
	(footprint "antmicro-footprints:UQFN-12_2x1.7mm_P0.4mm_Texas_RUT"
		(layer "F.Cu")
		(at 89.192962 152.3165 90)
		(descr "Texas_R_PUQFN-N12")
		(tags "Texas_R_PUQFN-N12")
		(property "Reference" "U203"
			(at 1.22 -1.445 180)
			(layer "F.SilkS")
			(effects
				(font
					(size 0.7 0.7)
					(thickness 0.15)
				)
				(justify left bottom)
			)
		)
		(property "Value" "TXB0104_UQFN"
			(at 0 2.35 90)
			(layer "F.Fab")
			(effects
				(font
					(size 0.7 0.7)
					(thickness 0.15)
				)
				(justify left bottom)
			)
		)
		(property "Datasheet" "http://www.ti.com/lit/ds/symlink/txb0104.pdf"
			(at 0 0 90)
			(layer "F.Fab")
			(hide yes)
			(effects
				(font
					(size 1.27 1.27)
					(thickness 0.15)
				)
			)
		)
		(property "Manufacturer" "Texas Instruments"
			(at 0 0 90)
			(unlocked yes)
			(layer "F.Fab")
			(hide yes)
			(effects
				(font
					(size 1 1)
					(thickness 0.15)
				)
			)
		)
		(property "MPN" "TXB0104RUTR"
			(at 0 0 90)
			(unlocked yes)
			(layer "F.Fab")
			(hide yes)
			(effects
				(font
					(size 1 1)
					(thickness 0.15)
				)
			)
		)
		(property "Author" "Antmicro"
			(at 0 0 90)
			(unlocked yes)
			(layer "F.Fab")
			(hide yes)
			(effects
				(font
					(size 1 1)
					(thickness 0.15)
				)
			)
		)
		(property "License" "Apache-2.0"
			(at 0 0 90)
			(unlocked yes)
			(layer "F.Fab")
			(hide yes)
			(effects
				(font
					(size 1 1)
					(thickness 0.15)
				)
			)
		)
		(property ki_fp_filters "Texas*R*PUQFN*N12*")
		(sheetname "/Compute module/")
		(sheetfile "compute-module.kicad_sch")
		(attr smd)
		(fp_line
			(start 0.597 -1.301)
			(end -0.55 -1.301)
			(stroke
				(width 0.15)
				(type solid)
			)
			(layer "F.SilkS")
		)
		(fp_line
			(start 0.497 1.3)
			(end -0.5 1.3)
			(stroke
				(width 0.15)
				(type solid)
			)
			(layer "F.SilkS")
		)
		(fp_circle
			(center -0.85 -1.2)
			(end -0.8 -1.2)
			(stroke
				(width 0.15)
				(type solid)
			)
			(fill yes)
			(layer "F.SilkS")
		)
		(fp_rect
			(start -1.1 -1.3)
			(end 1.1 1.3)
			(stroke
				(width 0.05)
				(type solid)
			)
			(fill no)
			(layer "F.CrtYd")
		)
		(fp_line
			(start 0.847 -1)
			(end 0.847 0.997)
			(stroke
				(width 0.15)
				(type solid)
			)
			(layer "F.Fab")
		)
		(fp_line
			(start -0.5 -1)
			(end 0.847 -1)
			(stroke
				(width 0.15)
				(type solid)
			)
			(layer "F.Fab")
		)
		(fp_line
			(start -0.5 -1)
			(end -0.85 -0.5)
			(stroke
				(width 0.15)
				(type solid)
			)
			(layer "F.Fab")
		)
		(fp_line
			(start 0.847 0.997)
			(end -0.85 0.997)
			(stroke
				(width 0.15)
				(type solid)
			)
			(layer "F.Fab")
		)
		(fp_line
			(start -0.85 0.997)
			(end -0.85 -0.5)
			(stroke
				(width 0.15)
				(type solid)
			)
			(layer "F.Fab")
		)
		(fp_text user "Author: Antmicro"
			(at -1.1 4.35 90)
			(layer "F.Fab")
			(effects
				(font
					(size 0.7 0.7)
					(thickness 0.15)
				)
				(justify left bottom)
			)
		)
		(fp_text user "License: Apache-2.0"
			(at -1.1 6.75 90)
			(layer "F.Fab")
			(effects
				(font
					(size 0.7 0.7)
					(thickness 0.15)
				)
				(justify left bottom)
			)
		)
		(fp_text user "${REFERENCE}"
			(at -1.1 5.55 90)
			(layer "F.Fab")
			(effects
				(font
					(size 0.7 0.7)
					(thickness 0.15)
				)
				(justify left bottom)
			)
		)
		(pad "1" smd rect
			(at -0.653 -0.803)
			(size 0.2 0.6)
			(layers "F.Cu" "F.Mask" "F.Paste")
			(net 18 "V_{IO}")
			(pinfunction "VCCA")
			(pintype "power_in")
		)
		(pad "1" smd rect
			(at -0.425 -0.975 90)
			(size 0.15 0.25)
			(layers "F.Cu" "F.Mask" "F.Paste")
			(net 18 "V_{IO}")
			(pinfunction "VCCA")
			(pintype "power_in")
		)
		(pad "2" smd rect
			(at -0.653 -0.403)
			(size 0.2 0.6)
			(layers "F.Cu" "F.Mask" "F.Paste")
			(net 239 "/Compute module/GPIO.14{slash}RXD0")
			(pinfunction "A1")
			(pintype "tri_state")
		)
		(pad "3" smd rect
			(at -0.653 0)
			(size 0.2 0.6)
			(layers "F.Cu" "F.Mask" "F.Paste")
			(net 241 "/Compute module/GPIO.15{slash}TXD0")
			(pinfunction "A2")
			(pintype "tri_state")
		)
		(pad "4" smd rect
			(at -0.653 0.4)
			(size 0.2 0.6)
			(layers "F.Cu" "F.Mask" "F.Paste")
			(net 224 "/Compute module/GPIO.12{slash}RXD5")
			(pinfunction "A3")
			(pintype "tri_state")
		)
		(pad "5" smd rect
			(at -0.653 0.8)
			(size 0.2 0.6)
			(layers "F.Cu" "F.Mask" "F.Paste")
			(net 221 "/Compute module/GPIO.13{slash}TXD5")
			(pinfunction "A4")
			(pintype "tri_state")
		)
		(pad "6" smd rect
			(at 0 0.8)
			(size 0.6 0.2)
			(layers "F.Cu" "F.Mask" "F.Paste")
			(net 3 "GND")
			(pinfunction "GND")
			(pintype "power_in")
		)
		(pad "7" smd rect
			(at 0.65 0.8)
			(size 0.2 0.6)
			(layers "F.Cu" "F.Mask" "F.Paste")
			(net 186 "/Compute module/UART.1.TX")
			(pinfunction "B4")
			(pintype "tri_state")
		)
		(pad "8" smd rect
			(at 0.65 0.4)
			(size 0.2 0.6)
			(layers "F.Cu" "F.Mask" "F.Paste")
			(net 187 "/Compute module/UART.1.RX")
			(pinfunction "B3")
			(pintype "tri_state")
		)
		(pad "9" smd rect
			(at 0.65 0)
			(size 0.2 0.6)
			(layers "F.Cu" "F.Mask" "F.Paste")
			(net 37 "/Compute module/UART.0.TX")
			(pinfunction "B2")
			(pintype "tri_state")
		)
		(pad "10" smd rect
			(at 0.65 -0.403)
			(size 0.2 0.6)
			(layers "F.Cu" "F.Mask" "F.Paste")
			(net 36 "/Compute module/UART.0.RX")
			(pinfunction "B1")
			(pintype "tri_state")
		)
		(pad "11" smd rect
			(at 0.65 -0.803)
			(size 0.2 0.6)
			(layers "F.Cu" "F.Mask" "F.Paste")
			(net 9 "+3V3")
			(pinfunction "VCCB")
			(pintype "power_in")
		)
		(pad "12" smd rect
			(at 0 -0.803)
			(size 0.6 0.2)
			(layers "F.Cu" "F.Mask" "F.Paste")
			(net 18 "V_{IO}")
			(pinfunction "OE")
			(pintype "input")
		)
	)
)
